# BASEBOARD_FAB2 (Tioga Pass) — schematic netlist excerpt (pin names and nets, part order shuffled) for the footprints in the layout excerpt that follows; sources: Cadence DE-HDL packaged netlist, KiCad conversion of Wiwynn_Tioga_Pass_MB.brd

R4P24  RES  150.0 1% CHIP  pkg 0402  page 112 : A = PVCCIO_CPU0 ; B = XDP_CPU_TDI
C2M13  CAP_A  22.0UF 4V 20% X6S  pkg 0603V  page 131 : A = P1V05_PCH_STBY ; B = GND
R6P41  RES  0.0 5% CHIP  pkg 0402  page 213 : A = FM_PVCCIO_CPU1_EN ; B = VR_PVCCIO_CPU1_EN

(kicad_pcb
	(version 20260206)
	(generator "pcbnew")
	(generator_version "10.0")
	(general
		(thickness 1.6)
		(legacy_teardrops no)
	)
	(paper "A4")
	(title_block
		(title "Wiwynn_Tioga_Pass_MB.brd")
		(comment 1 "Tioga Pass / footprints 3600-3602 of 4770")
	)
	(layers
		(0 "F.Cu" signal "TOP")
		(4 "In1.Cu" signal "L2GND")
		(6 "In2.Cu" signal "L3")
		(8 "In3.Cu" signal "L4GND")
		(10 "In4.Cu" signal "L5")
		(12 "In5.Cu" signal "L6GND")
		(14 "In6.Cu" signal "L7VCC")
		(16 "In7.Cu" signal "L8VCC")
		(18 "In8.Cu" signal "L9GND")
		(20 "In9.Cu" signal "L10")
		(22 "In10.Cu" signal "L11GND")
		(24 "In11.Cu" signal "L12")
		(26 "In12.Cu" signal "L13GND")
		(2 "B.Cu" signal "BOTTOM")
		(9 "F.Adhes" user "F.Adhesive")
		(11 "B.Adhes" user "B.Adhesive")
		(13 "F.Paste" user "Package Geometry/Pastemask Top")
		(15 "B.Paste" user "Package Geometry/Pastemask Bottom")
		(5 "F.SilkS" user "Ref Des/Silkscreen Top")
		(7 "B.SilkS" user "Ref Des/Silkscreen Bottom")
		(1 "F.Mask" user "Board Geometry/Soldermask Top")
		(3 "B.Mask" user "Board Geometry/Soldermask Bottom")
		(17 "Dwgs.User" user "User.Drawings")
		(19 "Cmts.User" user "User.Comments")
		(21 "Eco1.User" user "User.Eco1")
		(23 "Eco2.User" user "User.Eco2")
		(25 "Edge.Cuts" user "Board Geometry/Outline")
		(27 "Margin" user)
		(31 "F.CrtYd" user "Package Geometry/Place Bound Top")
		(29 "B.CrtYd" user "Package Geometry/Place Bound Bottom")
		(35 "F.Fab" user "Ref Des/Assembly Top")
		(33 "B.Fab" user "Ref Des/Assembly Bottom")
	)
	(footprint ""
		(layer "B.Cu")
		(at 293.881302 -65.417192)
		(property "Reference" "R4P24"
			(at 0 0 0)
			(layer "B.SilkS")
			(hide yes)
			(effects
				(font
					(size 1.27 1.27)
				)
				(justify mirror)
			)
		)
		(property "Value" ""
			(at 0 0 0)
			(layer "B.Fab")
			(effects
				(font
					(size 1.27 1.27)
				)
				(justify mirror)
			)
		)
		(duplicate_pad_numbers_are_jumpers no)
		(fp_rect
			(start 0.2794 -0.1016)
			(end -0.2794 0.9906)
			(stroke
				(width 0)
				(type default)
			)
			(fill no)
			(layer "B.CrtYd")
		)
		(fp_line
			(start -0.2794 -0.1016)
			(end 0.2794 -0.1016)
			(stroke
				(width 0.1)
				(type default)
			)
			(layer "B.Fab")
		)
		(fp_line
			(start -0.2794 0.9906)
			(end -0.2794 -0.1016)
			(stroke
				(width 0.1)
				(type default)
			)
			(layer "B.Fab")
		)
		(fp_line
			(start 0.2794 -0.1016)
			(end 0.2794 0.9906)
			(stroke
				(width 0.1)
				(type default)
			)
			(layer "B.Fab")
		)
		(fp_line
			(start 0.2794 0.9906)
			(end -0.2794 0.9906)
			(stroke
				(width 0.1)
				(type default)
			)
			(layer "B.Fab")
		)
		(pad "1" smd rect
			(at 0 0 180)
			(size 0.508 0.508)
			(layers "B.Cu" "B.Mask" "B.Paste")
			(net "PVCCIO_CPU0")
		)
		(pad "2" smd rect
			(at 0 0.889 180)
			(size 0.508 0.508)
			(layers "B.Cu" "B.Mask" "B.Paste")
			(net "XDP_CPU_TDI")
		)
		(zone
			(layer "B.Cu")
			(hatch none 0.5)
			(connect_pads
				(clearance 0)
			)
			(min_thickness 0.25)
			(keepout
				(tracks not_allowed)
				(vias allowed)
				(pads allowed)
				(copperpour not_allowed)
				(footprints allowed)
			)
			(placement
				(enabled no)
				(sheetname "")
			)
			(fill
				(thermal_gap 0.5)
				(thermal_bridge_width 0.5)
				(island_removal_mode 0)
			)
			(polygon
				(pts
					(xy 294.135302 -65.163192) (xy 293.627302 -65.163192) (xy 293.627302 -64.782192) (xy 294.135302 -64.782192)
				)
			)
		)
		(zone
			(layer "B.Cu")
			(hatch none 0.5)
			(connect_pads
				(clearance 0)
			)
			(min_thickness 0.25)
			(keepout
				(tracks allowed)
				(vias not_allowed)
				(pads allowed)
				(copperpour not_allowed)
				(footprints allowed)
			)
			(placement
				(enabled no)
				(sheetname "")
			)
			(fill
				(thermal_gap 0.5)
				(thermal_bridge_width 0.5)
				(island_removal_mode 0)
			)
			(polygon
				(pts
					(xy 294.135302 -65.163192) (xy 293.627302 -65.163192) (xy 293.627302 -64.782192) (xy 294.135302 -64.782192)
				)
			)
		)
	)
	(footprint ""
		(layer "B.Cu")
		(at 404.0378 -116.7765 180)
		(property "Reference" "C2M13"
			(at 0 0 0)
			(layer "B.SilkS")
			(hide yes)
			(effects
				(font
					(size 1.27 1.27)
				)
				(justify mirror)
			)
		)
		(property "Value" ""
			(at 0 0 0)
			(layer "B.Fab")
			(effects
				(font
					(size 1.27 1.27)
				)
				(justify mirror)
			)
		)
		(duplicate_pad_numbers_are_jumpers no)
		(fp_poly
			(pts
				(xy 0.4953 -0.2032) (xy -0.4953 -0.2032) (xy -0.4953 1.6002) (xy 0.4953 1.6002)
			)
			(stroke
				(width 0)
				(type default)
			)
			(fill no)
			(layer "B.CrtYd")
		)
		(fp_line
			(start 0.4953 1.6002)
			(end 0.4953 -0.2032)
			(stroke
				(width 0.1)
				(type default)
			)
			(layer "B.Fab")
		)
		(fp_line
			(start 0.4953 -0.2032)
			(end -0.4953 -0.2032)
			(stroke
				(width 0.1)
				(type default)
			)
			(layer "B.Fab")
		)
		(fp_line
			(start -0.4953 1.6002)
			(end 0.4953 1.6002)
			(stroke
				(width 0.1)
				(type default)
			)
			(layer "B.Fab")
		)
		(fp_line
			(start -0.4953 -0.2032)
			(end -0.4953 1.6002)
			(stroke
				(width 0.1)
				(type default)
			)
			(layer "B.Fab")
		)
		(pad "1" smd rect
			(at 0 0)
			(size 0.762 0.889)
			(layers "B.Cu" "B.Mask" "B.Paste")
			(net "P1V05_PCH_STBY")
		)
		(pad "2" smd rect
			(at 0 1.397)
			(size 0.762 0.889)
			(layers "B.Cu" "B.Mask" "B.Paste")
			(net "GND")
		)
		(zone
			(layer "B.Cu")
			(hatch none 0.5)
			(connect_pads
				(clearance 0)
			)
			(min_thickness 0.25)
			(keepout
				(tracks not_allowed)
				(vias allowed)
				(pads allowed)
				(copperpour not_allowed)
				(footprints allowed)
			)
			(placement
				(enabled no)
				(sheetname "")
			)
			(fill
				(thermal_gap 0.5)
				(thermal_bridge_width 0.5)
				(island_removal_mode 0)
			)
			(polygon
				(pts
					(xy 403.6568 -117.221) (xy 404.4188 -117.221) (xy 404.4188 -117.729) (xy 403.6568 -117.729)
				)
			)
		)
	)
	(footprint ""
		(layer "B.Cu")
		(at 164.973 -66.3702 90)
		(property "Reference" "R6P41"
			(at 0 0 90)
			(layer "B.SilkS")
			(hide yes)
			(effects
				(font
					(size 1.27 1.27)
				)
				(justify mirror)
			)
		)
		(property "Value" ""
			(at 0 0 90)
			(layer "B.Fab")
			(effects
				(font
					(size 1.27 1.27)
				)
				(justify mirror)
			)
		)
		(duplicate_pad_numbers_are_jumpers no)
		(fp_poly
			(pts
				(xy 0.2794 -0.1016) (xy -0.2794 -0.1016) (xy -0.2794 0.9906) (xy 0.2794 0.9906)
			)
			(stroke
				(width 0)
				(type default)
			)
			(fill no)
			(layer "B.CrtYd")
		)
		(fp_line
			(start 0.2794 -0.1016)
			(end 0.2794 0.9906)
			(stroke
				(width 0.1)
				(type default)
			)
			(layer "B.Fab")
		)
		(fp_line
			(start -0.2794 -0.1016)
			(end 0.2794 -0.1016)
			(stroke
				(width 0.1)
				(type default)
			)
			(layer "B.Fab")
		)
		(fp_line
			(start 0.2794 0.9906)
			(end -0.2794 0.9906)
			(stroke
				(width 0.1)
				(type default)
			)
			(layer "B.Fab")
		)
		(fp_line
			(start -0.2794 0.9906)
			(end -0.2794 -0.1016)
			(stroke
				(width 0.1)
				(type default)
			)
			(layer "B.Fab")
		)
		(pad "1" smd rect
			(at 0 0 270)
			(size 0.508 0.508)
			(layers "B.Cu" "B.Mask" "B.Paste")
			(net "FM_PVCCIO_CPU1_EN")
		)
		(pad "2" smd rect
			(at 0 0.889 270)
			(size 0.508 0.508)
			(layers "B.Cu" "B.Mask" "B.Paste")
			(net "VR_PVCCIO_CPU1_EN")
		)
		(zone
			(layer "B.Cu")
			(hatch none 0.5)
			(connect_pads
				(clearance 0)
			)
			(min_thickness 0.25)
			(keepout
				(tracks allowed)
				(vias not_allowed)
				(pads allowed)
				(copperpour not_allowed)
				(footprints allowed)
			)
			(placement
				(enabled no)
				(sheetname "")
			)
			(fill
				(thermal_gap 0.5)
				(thermal_bridge_width 0.5)
				(island_removal_mode 0)
			)
			(polygon
				(pts
					(xy 165.227 -66.6242) (xy 165.227 -66.1162) (xy 165.608 -66.1162) (xy 165.608 -66.6242)
				)
			)
		)
		(zone
			(layer "B.Cu")
			(hatch none 0.5)
			(connect_pads
				(clearance 0)
			)
			(min_thickness 0.25)
			(keepout
				(tracks not_allowed)
				(vias allowed)
				(pads allowed)
				(copperpour not_allowed)
				(footprints allowed)
			)
			(placement
				(enabled no)
				(sheetname "")
			)
			(fill
				(thermal_gap 0.5)
				(thermal_bridge_width 0.5)
				(island_removal_mode 0)
			)
			(polygon
				(pts
					(xy 165.608 -66.6242) (xy 165.608 -66.1162) (xy 165.227 -66.1162) (xy 165.227 -66.6242)
				)
			)
		)
	)
)
